# T6G (Grand Teton) — schematic netlist excerpt (pin names and nets, part order shuffled) for the footprints in the layout excerpt that follows; sources: Cadence DE-HDL packaged netlist, KiCad conversion of 04192023_DAF0TMB3IC0_F0TG_MB_C_brd_V02_OCP.brd

R6241  Q_RES  0 5% CHIP  pkg 0402LF  page 270 : A = PWRGD_P1V2_AUX ; B = PWRGD_P1V2_AUX_R
C2416  Q_CAP  22UF 4V 20% X6S  pkg C0402  page 74 : A = PVDDCR_SOC_P1 ; B = GND

(kicad_pcb
	(version 20260206)
	(generator "pcbnew")
	(generator_version "10.0")
	(general
		(thickness 1.6)
		(legacy_teardrops no)
	)
	(paper "A4")
	(title_block
		(title "04192023_DAF0TMB3IC0_F0TG_MB_C_brd_V02_OCP.brd")
		(comment 1 "Grand Teton / footprints 7689-7690 of 8354")
	)
	(layers
		(0 "F.Cu" signal "TOP")
		(4 "In1.Cu" signal "GND")
		(6 "In2.Cu" signal "IN1")
		(8 "In3.Cu" signal "GND1")
		(10 "In4.Cu" signal "IN2")
		(12 "In5.Cu" signal "GND2")
		(14 "In6.Cu" signal "IN3")
		(16 "In7.Cu" signal "GND3")
		(18 "In8.Cu" signal "VCC")
		(20 "In9.Cu" signal "VCC1")
		(22 "In10.Cu" signal "GND4")
		(24 "In11.Cu" signal "IN4")
		(26 "In12.Cu" signal "GND5")
		(28 "In13.Cu" signal "IN5")
		(30 "In14.Cu" signal "GND6")
		(32 "In15.Cu" signal "IN6")
		(34 "In16.Cu" signal "GND7")
		(2 "B.Cu" signal "BOTTOM")
		(9 "F.Adhes" user "F.Adhesive")
		(11 "B.Adhes" user "B.Adhesive")
		(13 "F.Paste" user "Package Geometry/Pastemask Top")
		(15 "B.Paste" user "Package Geometry/Pastemask Bottom")
		(5 "F.SilkS" user "Ref Des/Silkscreen Top")
		(7 "B.SilkS" user "Ref Des/Silkscreen Bottom")
		(1 "F.Mask" user "Board Geometry/Soldermask Top")
		(3 "B.Mask" user "Board Geometry/Soldermask Bottom")
		(17 "Dwgs.User" user "User.Drawings")
		(19 "Cmts.User" user "User.Comments")
		(21 "Eco1.User" user "User.Eco1")
		(23 "Eco2.User" user "User.Eco2")
		(25 "Edge.Cuts" user "Board Geometry/Outline")
		(27 "Margin" user)
		(31 "F.CrtYd" user "Package Geometry/Place Bound Top")
		(29 "B.CrtYd" user "Package Geometry/Place Bound Bottom")
		(35 "F.Fab" user "Ref Des/Assembly Top")
		(33 "B.Fab" user "Ref Des/Assembly Bottom")
	)
	(footprint ""
		(layer "B.Cu")
		(at 124.459492 -72.616822 180)
		(property "Reference" "R6241"
			(at 0 0 0)
			(layer "B.SilkS")
			(hide yes)
			(effects
				(font
					(size 1.27 1.27)
				)
				(justify mirror)
			)
		)
		(property "Value" ""
			(at 0 0 0)
			(layer "B.Fab")
			(effects
				(font
					(size 1.27 1.27)
				)
				(justify mirror)
			)
		)
		(duplicate_pad_numbers_are_jumpers no)
		(fp_line
			(start 0.7874 0.4064)
			(end 0.7874 -0.4064)
			(stroke
				(width 0.1524)
				(type default)
			)
			(layer "B.SilkS")
		)
		(fp_line
			(start 0.7874 -0.4064)
			(end -0.7874 -0.4064)
			(stroke
				(width 0.1524)
				(type default)
			)
			(layer "B.SilkS")
		)
		(fp_line
			(start -0.7874 0.4064)
			(end 0.7874 0.4064)
			(stroke
				(width 0.1524)
				(type default)
			)
			(layer "B.SilkS")
		)
		(fp_line
			(start -0.7874 -0.4064)
			(end -0.7874 0.4064)
			(stroke
				(width 0.1524)
				(type default)
			)
			(layer "B.SilkS")
		)
		(fp_line
			(start 0.67945 0.3048)
			(end 0.67945 -0.305054)
			(stroke
				(width 0.1)
				(type default)
			)
			(layer "B.Fab")
		)
		(fp_line
			(start 0.67945 -0.305054)
			(end 0.12065 -0.305054)
			(stroke
				(width 0.1)
				(type default)
			)
			(layer "B.Fab")
		)
		(fp_line
			(start 0.12065 0.3048)
			(end 0.67945 0.3048)
			(stroke
				(width 0.1)
				(type default)
			)
			(layer "B.Fab")
		)
		(fp_line
			(start 0.12065 0.2794)
			(end 0.12065 0.3048)
			(stroke
				(width 0.1)
				(type default)
			)
			(layer "B.Fab")
		)
		(fp_line
			(start 0.12065 -0.2794)
			(end -0.12065 -0.2794)
			(stroke
				(width 0.1)
				(type default)
			)
			(layer "B.Fab")
		)
		(fp_line
			(start 0.12065 -0.305054)
			(end 0.12065 -0.2794)
			(stroke
				(width 0.1)
				(type default)
			)
			(layer "B.Fab")
		)
		(fp_line
			(start -0.120396 0.3048)
			(end -0.120396 0.2794)
			(stroke
				(width 0.1)
				(type default)
			)
			(layer "B.Fab")
		)
		(fp_line
			(start -0.120396 0.2794)
			(end 0.12065 0.2794)
			(stroke
				(width 0.1)
				(type default)
			)
			(layer "B.Fab")
		)
		(fp_line
			(start -0.12065 -0.2794)
			(end -0.12065 -0.3048)
			(stroke
				(width 0.1)
				(type default)
			)
			(layer "B.Fab")
		)
		(fp_line
			(start -0.12065 -0.3048)
			(end -0.67945 -0.3048)
			(stroke
				(width 0.1)
				(type default)
			)
			(layer "B.Fab")
		)
		(fp_line
			(start -0.67945 0.3048)
			(end -0.120396 0.3048)
			(stroke
				(width 0.1)
				(type default)
			)
			(layer "B.Fab")
		)
		(fp_line
			(start -0.67945 -0.3048)
			(end -0.67945 0.3048)
			(stroke
				(width 0.1)
				(type default)
			)
			(layer "B.Fab")
		)
		(pad "1" smd circle
			(at 0.40005 0)
			(size 0 0)
			(layers "B.Cu" "B.Mask" "B.Paste")
			(net "PWRGD_P1V2_AUX")
		)
		(pad "2" smd circle
			(at -0.40005 0)
			(size 0 0)
			(layers "B.Cu" "B.Mask" "B.Paste")
			(net "PWRGD_P1V2_AUX_R")
		)
	)
	(footprint ""
		(layer "B.Cu")
		(at 103.672386 -262.703564 180)
		(property "Reference" "C2416"
			(at 0 0 0)
			(layer "B.SilkS")
			(hide yes)
			(effects
				(font
					(size 1.27 1.27)
				)
				(justify mirror)
			)
		)
		(property "Value" ""
			(at 0 0 0)
			(layer "B.Fab")
			(effects
				(font
					(size 1.27 1.27)
				)
				(justify mirror)
			)
		)
		(duplicate_pad_numbers_are_jumpers no)
		(fp_line
			(start 0.7874 0.4064)
			(end 0.7874 -0.4064)
			(stroke
				(width 0.1524)
				(type default)
			)
			(layer "B.SilkS")
		)
		(fp_line
			(start 0.7874 -0.4064)
			(end -0.7874 -0.4064)
			(stroke
				(width 0.1524)
				(type default)
			)
			(layer "B.SilkS")
		)
		(fp_line
			(start -0.7874 0.4064)
			(end 0.7874 0.4064)
			(stroke
				(width 0.1524)
				(type default)
			)
			(layer "B.SilkS")
		)
		(fp_line
			(start -0.7874 -0.4064)
			(end -0.7874 0.4064)
			(stroke
				(width 0.1524)
				(type default)
			)
			(layer "B.SilkS")
		)
		(fp_line
			(start 0.67945 0.3048)
			(end 0.67945 -0.305054)
			(stroke
				(width 0.1)
				(type default)
			)
			(layer "B.Fab")
		)
		(fp_line
			(start 0.67945 -0.305054)
			(end 0.12065 -0.305054)
			(stroke
				(width 0.1)
				(type default)
			)
			(layer "B.Fab")
		)
		(fp_line
			(start 0.12065 0.3048)
			(end 0.67945 0.3048)
			(stroke
				(width 0.1)
				(type default)
			)
			(layer "B.Fab")
		)
		(fp_line
			(start 0.12065 0.2794)
			(end 0.12065 0.3048)
			(stroke
				(width 0.1)
				(type default)
			)
			(layer "B.Fab")
		)
		(fp_line
			(start 0.12065 -0.2794)
			(end -0.12065 -0.2794)
			(stroke
				(width 0.1)
				(type default)
			)
			(layer "B.Fab")
		)
		(fp_line
			(start 0.12065 -0.305054)
			(end 0.12065 -0.2794)
			(stroke
				(width 0.1)
				(type default)
			)
			(layer "B.Fab")
		)
		(fp_line
			(start -0.120396 0.3048)
			(end -0.120396 0.2794)
			(stroke
				(width 0.1)
				(type default)
			)
			(layer "B.Fab")
		)
		(fp_line
			(start -0.120396 0.2794)
			(end 0.12065 0.2794)
			(stroke
				(width 0.1)
				(type default)
			)
			(layer "B.Fab")
		)
		(fp_line
			(start -0.12065 -0.2794)
			(end -0.12065 -0.3048)
			(stroke
				(width 0.1)
				(type default)
			)
			(layer "B.Fab")
		)
		(fp_line
			(start -0.12065 -0.3048)
			(end -0.67945 -0.3048)
			(stroke
				(width 0.1)
				(type default)
			)
			(layer "B.Fab")
		)
		(fp_line
			(start -0.67945 0.3048)
			(end -0.120396 0.3048)
			(stroke
				(width 0.1)
				(type default)
			)
			(layer "B.Fab")
		)
		(fp_line
			(start -0.67945 -0.3048)
			(end -0.67945 0.3048)
			(stroke
				(width 0.1)
				(type default)
			)
			(layer "B.Fab")
		)
		(pad "1" smd circle
			(at 0.40005 0)
			(size 0 0)
			(layers "B.Cu" "B.Mask" "B.Paste")
			(net "PVDDCR_SOC_P1")
		)
		(pad "2" smd circle
			(at -0.40005 0)
			(size 0 0)
			(layers "B.Cu" "B.Mask" "B.Paste")
			(net "GND")
		)
	)
)
